# S9S_MB_2U (Grand Teton) — schematic netlist excerpt (pin names and nets, part order shuffled) for the footprints in the layout excerpt that follows; sources: Cadence DE-HDL packaged netlist, KiCad conversion of 03242023_DA0F0TMBIJ0_F0T_Motherboard_J_brd_V01_OCP.brd

PR1804  Q_RES  3.3 1% CHIP  pkg 0402LF  page 297 : A = SW_PVCCD_HV_CPU1_BOOT1 ; B = SW_PVCCD_HV_CPU1_BOOT1_R
R3056  Q_RES  33.2 1% CHIP  pkg 0402LF  page 239 : A = JTAG_DBP_BMC_PRDY_R1_N ; B = JTAG_DBP_BMC_PRDY_N

(kicad_pcb
	(version 20260206)
	(generator "pcbnew")
	(generator_version "10.0")
	(general
		(thickness 1.6)
		(legacy_teardrops no)
	)
	(paper "A4")
	(title_block
		(title "03242023_DA0F0TMBIJ0_F0T_Motherboard_J_brd_V01_OCP.brd")
		(comment 1 "Grand Teton / footprints 2317-2318 of 6105")
	)
	(layers
		(0 "F.Cu" signal "TOP")
		(4 "In1.Cu" signal "GND")
		(6 "In2.Cu" signal "IN1")
		(8 "In3.Cu" signal "GND1")
		(10 "In4.Cu" signal "IN2")
		(12 "In5.Cu" signal "GND2")
		(14 "In6.Cu" signal "IN3")
		(16 "In7.Cu" signal "GND3")
		(18 "In8.Cu" signal "VCC")
		(20 "In9.Cu" signal "VCC1")
		(22 "In10.Cu" signal "GND4")
		(24 "In11.Cu" signal "IN4")
		(26 "In12.Cu" signal "GND5")
		(28 "In13.Cu" signal "IN5")
		(30 "In14.Cu" signal "GND6")
		(32 "In15.Cu" signal "IN6")
		(34 "In16.Cu" signal "GND7")
		(2 "B.Cu" signal "BOTTOM")
		(9 "F.Adhes" user "F.Adhesive")
		(11 "B.Adhes" user "B.Adhesive")
		(13 "F.Paste" user "Package Geometry/Pastemask Top")
		(15 "B.Paste" user "Package Geometry/Pastemask Bottom")
		(5 "F.SilkS" user "Ref Des/Silkscreen Top")
		(7 "B.SilkS" user "Ref Des/Silkscreen Bottom")
		(1 "F.Mask" user "Board Geometry/Soldermask Top")
		(3 "B.Mask" user "Board Geometry/Soldermask Bottom")
		(17 "Dwgs.User" user "User.Drawings")
		(19 "Cmts.User" user "User.Comments")
		(21 "Eco1.User" user "User.Eco1")
		(23 "Eco2.User" user "User.Eco2")
		(25 "Edge.Cuts" user "Board Geometry/Outline")
		(27 "Margin" user)
		(31 "F.CrtYd" user "Package Geometry/Place Bound Top")
		(29 "B.CrtYd" user "Package Geometry/Place Bound Bottom")
		(35 "F.Fab" user "Ref Des/Assembly Top")
		(33 "B.Fab" user "Ref Des/Assembly Bottom")
	)
	(footprint ""
		(layer "F.Cu")
		(at 50.43551 -165.808914 180)
		(property "Reference" "PR1804"
			(at 0 0 180)
			(layer "F.SilkS")
			(hide yes)
			(effects
				(font
					(size 1.27 1.27)
				)
			)
		)
		(property "Value" ""
			(at 0 0 180)
			(layer "F.Fab")
			(effects
				(font
					(size 1.27 1.27)
				)
			)
		)
		(duplicate_pad_numbers_are_jumpers no)
		(fp_line
			(start 0.7874 0.4064)
			(end -0.7874 0.4064)
			(stroke
				(width 0.1524)
				(type default)
			)
			(layer "F.SilkS")
		)
		(fp_line
			(start 0.7874 -0.4064)
			(end 0.7874 0.4064)
			(stroke
				(width 0.1524)
				(type default)
			)
			(layer "F.SilkS")
		)
		(fp_line
			(start -0.7874 0.4064)
			(end -0.7874 -0.4064)
			(stroke
				(width 0.1524)
				(type default)
			)
			(layer "F.SilkS")
		)
		(fp_line
			(start -0.7874 -0.4064)
			(end 0.7874 -0.4064)
			(stroke
				(width 0.1524)
				(type default)
			)
			(layer "F.SilkS")
		)
		(fp_line
			(start 0.67945 0.3048)
			(end 0.120396 0.3048)
			(stroke
				(width 0.1)
				(type default)
			)
			(layer "F.Fab")
		)
		(fp_line
			(start 0.67945 -0.3048)
			(end 0.67945 0.3048)
			(stroke
				(width 0.1)
				(type default)
			)
			(layer "F.Fab")
		)
		(fp_line
			(start 0.12065 -0.2794)
			(end 0.12065 -0.3048)
			(stroke
				(width 0.1)
				(type default)
			)
			(layer "F.Fab")
		)
		(fp_line
			(start 0.12065 -0.3048)
			(end 0.67945 -0.3048)
			(stroke
				(width 0.1)
				(type default)
			)
			(layer "F.Fab")
		)
		(fp_line
			(start 0.120396 0.3048)
			(end 0.120396 0.2794)
			(stroke
				(width 0.1)
				(type default)
			)
			(layer "F.Fab")
		)
		(fp_line
			(start 0.120396 0.2794)
			(end -0.12065 0.2794)
			(stroke
				(width 0.1)
				(type default)
			)
			(layer "F.Fab")
		)
		(fp_line
			(start -0.12065 0.3048)
			(end -0.67945 0.3048)
			(stroke
				(width 0.1)
				(type default)
			)
			(layer "F.Fab")
		)
		(fp_line
			(start -0.12065 0.2794)
			(end -0.12065 0.3048)
			(stroke
				(width 0.1)
				(type default)
			)
			(layer "F.Fab")
		)
		(fp_line
			(start -0.12065 -0.2794)
			(end 0.12065 -0.2794)
			(stroke
				(width 0.1)
				(type default)
			)
			(layer "F.Fab")
		)
		(fp_line
			(start -0.12065 -0.305054)
			(end -0.12065 -0.2794)
			(stroke
				(width 0.1)
				(type default)
			)
			(layer "F.Fab")
		)
		(fp_line
			(start -0.67945 0.3048)
			(end -0.67945 -0.305054)
			(stroke
				(width 0.1)
				(type default)
			)
			(layer "F.Fab")
		)
		(fp_line
			(start -0.67945 -0.305054)
			(end -0.12065 -0.305054)
			(stroke
				(width 0.1)
				(type default)
			)
			(layer "F.Fab")
		)
		(pad "1" smd circle
			(at -0.40005 0 180)
			(size 0 0)
			(layers "F.Cu" "F.Mask" "F.Paste")
			(net "SW_PVCCD_HV_CPU1_BOOT1")
		)
		(pad "2" smd circle
			(at 0.40005 0 180)
			(size 0 0)
			(layers "F.Cu" "F.Mask" "F.Paste")
			(net "SW_PVCCD_HV_CPU1_BOOT1_R")
		)
	)
	(footprint ""
		(layer "F.Cu")
		(at 378.349256 -92.887292 -90)
		(property "Reference" "R3056"
			(at 0 0 270)
			(layer "F.SilkS")
			(hide yes)
			(effects
				(font
					(size 1.27 1.27)
				)
			)
		)
		(property "Value" ""
			(at 0 0 270)
			(layer "F.Fab")
			(effects
				(font
					(size 1.27 1.27)
				)
			)
		)
		(duplicate_pad_numbers_are_jumpers no)
		(fp_line
			(start -0.7874 0.4064)
			(end -0.7874 -0.4064)
			(stroke
				(width 0.1524)
				(type default)
			)
			(layer "F.SilkS")
		)
		(fp_line
			(start 0.7874 0.4064)
			(end -0.7874 0.4064)
			(stroke
				(width 0.1524)
				(type default)
			)
			(layer "F.SilkS")
		)
		(fp_line
			(start -0.7874 -0.4064)
			(end 0.7874 -0.4064)
			(stroke
				(width 0.1524)
				(type default)
			)
			(layer "F.SilkS")
		)
		(fp_line
			(start 0.7874 -0.4064)
			(end 0.7874 0.4064)
			(stroke
				(width 0.1524)
				(type default)
			)
			(layer "F.SilkS")
		)
		(fp_line
			(start -0.67945 0.3048)
			(end -0.67945 -0.305054)
			(stroke
				(width 0.1)
				(type default)
			)
			(layer "F.Fab")
		)
		(fp_line
			(start -0.12065 0.3048)
			(end -0.67945 0.3048)
			(stroke
				(width 0.1)
				(type default)
			)
			(layer "F.Fab")
		)
		(fp_line
			(start 0.120396 0.3048)
			(end 0.120396 0.2794)
			(stroke
				(width 0.1)
				(type default)
			)
			(layer "F.Fab")
		)
		(fp_line
			(start 0.67945 0.3048)
			(end 0.120396 0.3048)
			(stroke
				(width 0.1)
				(type default)
			)
			(layer "F.Fab")
		)
		(fp_line
			(start -0.12065 0.2794)
			(end -0.12065 0.3048)
			(stroke
				(width 0.1)
				(type default)
			)
			(layer "F.Fab")
		)
		(fp_line
			(start 0.120396 0.2794)
			(end -0.12065 0.2794)
			(stroke
				(width 0.1)
				(type default)
			)
			(layer "F.Fab")
		)
		(fp_line
			(start -0.12065 -0.2794)
			(end 0.12065 -0.2794)
			(stroke
				(width 0.1)
				(type default)
			)
			(layer "F.Fab")
		)
		(fp_line
			(start 0.12065 -0.2794)
			(end 0.12065 -0.3048)
			(stroke
				(width 0.1)
				(type default)
			)
			(layer "F.Fab")
		)
		(fp_line
			(start 0.12065 -0.3048)
			(end 0.67945 -0.3048)
			(stroke
				(width 0.1)
				(type default)
			)
			(layer "F.Fab")
		)
		(fp_line
			(start 0.67945 -0.3048)
			(end 0.67945 0.3048)
			(stroke
				(width 0.1)
				(type default)
			)
			(layer "F.Fab")
		)
		(fp_line
			(start -0.67945 -0.305054)
			(end -0.12065 -0.305054)
			(stroke
				(width 0.1)
				(type default)
			)
			(layer "F.Fab")
		)
		(fp_line
			(start -0.12065 -0.305054)
			(end -0.12065 -0.2794)
			(stroke
				(width 0.1)
				(type default)
			)
			(layer "F.Fab")
		)
		(pad "1" smd circle
			(at -0.40005 0 270)
			(size 0 0)
			(layers "F.Cu" "F.Mask" "F.Paste")
			(net "JTAG_DBP_BMC_PRDY_R1_N")
		)
		(pad "2" smd circle
			(at 0.40005 0 270)
			(size 0 0)
			(layers "F.Cu" "F.Mask" "F.Paste")
			(net "JTAG_DBP_BMC_PRDY_N")
		)
	)
)
